(kicad_sch
	(version 20231120)
	(generator "eeschema")
	(generator_version "8.0")
	(paper "A3")
	(title_block
		(title "GSML Serializer ")
		(date "2024-11-27")
		(rev "1.1.1")
		(company "Antmicro Ltd")
		(comment 1 "www.antmicro.com")
	)
	(junction
		(at 133.35 111.76)
		(diameter 0)
		(color 0 0 0 0)
	)
	(junction
		(at 238.76 111.76)
		(diameter 0)
		(color 0 0 0 0)
	)
	(junction
		(at 251.46 111.76)
		(diameter 0)
		(color 0 0 0 0)
	)
	(junction
		(at 203.2 111.76)
		(diameter 0)
		(color 0 0 0 0)
	)
	(junction
		(at 246.38 111.76)
		(diameter 0)
		(color 0 0 0 0)
	)
	(junction
		(at 259.08 111.76)
		(diameter 0)
		(color 0 0 0 0)
	)
	(junction
		(at 151.13 111.76)
		(diameter 0)
		(color 0 0 0 0)
	)
	(junction
		(at 220.98 121.92)
		(diameter 0)
		(color 0 0 0 0)
	)
	(junction
		(at 220.98 111.76)
		(diameter 0)
		(color 0 0 0 0)
	)
	(wire
		(pts
			(xy 220.98 111.76) (xy 214.63 111.76)
		)
		(stroke
			(width 0)
			(type default)
		)
	)
	(wire
		(pts
			(xy 133.35 111.76) (xy 133.35 118.11)
		)
		(stroke
			(width 0)
			(type default)
		)
	)
	(wire
		(pts
			(xy 191.77 111.76) (xy 179.07 111.76)
		)
		(stroke
			(width 0)
			(type default)
		)
	)
	(wire
		(pts
			(xy 232.41 121.92) (xy 238.76 121.92)
		)
		(stroke
			(width 0)
			(type default)
		)
	)
	(wire
		(pts
			(xy 120.65 116.84) (xy 120.65 118.11)
		)
		(stroke
			(width 0)
			(type default)
		)
	)
	(wire
		(pts
			(xy 209.55 121.92) (xy 203.2 121.92)
		)
		(stroke
			(width 0)
			(type default)
		)
	)
	(wire
		(pts
			(xy 251.46 119.38) (xy 251.46 120.65)
		)
		(stroke
			(width 0)
			(type default)
		)
	)
	(wire
		(pts
			(xy 203.2 111.76) (xy 196.85 111.76)
		)
		(stroke
			(width 0)
			(type default)
		)
	)
	(wire
		(pts
			(xy 259.08 111.76) (xy 251.46 111.76)
		)
		(stroke
			(width 0)
			(type default)
		)
	)
	(wire
		(pts
			(xy 151.13 111.76) (xy 173.99 111.76)
		)
		(stroke
			(width 0)
			(type default)
		)
	)
	(wire
		(pts
			(xy 133.35 111.76) (xy 151.13 111.76)
		)
		(stroke
			(width 0)
			(type default)
		)
	)
	(wire
		(pts
			(xy 220.98 121.92) (xy 220.98 111.76)
		)
		(stroke
			(width 0)
			(type default)
		)
	)
	(wire
		(pts
			(xy 227.33 121.92) (xy 220.98 121.92)
		)
		(stroke
			(width 0)
			(type default)
		)
	)
	(wire
		(pts
			(xy 220.98 111.76) (xy 227.33 111.76)
		)
		(stroke
			(width 0)
			(type default)
		)
	)
	(wire
		(pts
			(xy 259.08 110.49) (xy 259.08 111.76)
		)
		(stroke
			(width 0)
			(type default)
		)
	)
	(wire
		(pts
			(xy 259.08 114.3) (xy 259.08 111.76)
		)
		(stroke
			(width 0)
			(type default)
		)
	)
	(wire
		(pts
			(xy 203.2 111.76) (xy 209.55 111.76)
		)
		(stroke
			(width 0)
			(type default)
		)
	)
	(wire
		(pts
			(xy 246.38 111.76) (xy 238.76 111.76)
		)
		(stroke
			(width 0)
			(type default)
		)
	)
	(wire
		(pts
			(xy 151.13 88.9) (xy 151.13 111.76)
		)
		(stroke
			(width 0)
			(type default)
		)
	)
	(wire
		(pts
			(xy 214.63 121.92) (xy 220.98 121.92)
		)
		(stroke
			(width 0)
			(type default)
		)
	)
	(wire
		(pts
			(xy 133.35 123.19) (xy 133.35 125.73)
		)
		(stroke
			(width 0)
			(type default)
		)
	)
	(wire
		(pts
			(xy 251.46 111.76) (xy 246.38 111.76)
		)
		(stroke
			(width 0)
			(type default)
		)
	)
	(wire
		(pts
			(xy 251.46 114.3) (xy 251.46 111.76)
		)
		(stroke
			(width 0)
			(type default)
		)
	)
	(wire
		(pts
			(xy 133.35 111.76) (xy 125.73 111.76)
		)
		(stroke
			(width 0)
			(type default)
		)
	)
	(wire
		(pts
			(xy 259.08 119.38) (xy 259.08 120.65)
		)
		(stroke
			(width 0)
			(type default)
		)
	)
	(wire
		(pts
			(xy 238.76 121.92) (xy 238.76 111.76)
		)
		(stroke
			(width 0)
			(type default)
		)
	)
	(wire
		(pts
			(xy 238.76 111.76) (xy 232.41 111.76)
		)
		(stroke
			(width 0)
			(type default)
		)
	)
	(wire
		(pts
			(xy 157.48 88.9) (xy 151.13 88.9)
		)
		(stroke
			(width 0)
			(type default)
		)
	)
	(wire
		(pts
			(xy 246.38 110.49) (xy 246.38 111.76)
		)
		(stroke
			(width 0)
			(type default)
		)
	)
	(wire
		(pts
			(xy 203.2 121.92) (xy 203.2 111.76)
		)
		(stroke
			(width 0)
			(type default)
		)
	)
	(text "FAKRA Connector"
		(exclude_from_sim no)
		(at 138.43 99.695 0)
		(effects
			(font
				(size 2.54 2.54)
				(thickness 0.508)
				(bold yes)
			)
			(justify right bottom)
		)
	)
	(text "PoC Filter"
		(exclude_from_sim no)
		(at 186.69 100.33 0)
		(effects
			(font
				(size 2.54 2.54)
				(thickness 0.508)
				(bold yes)
			)
			(justify left bottom)
		)
	)
	(hierarchical_label "SIO_P"
		(shape bidirectional)
		(at 157.48 88.9 0)
		(fields_autoplaced yes)
		(effects
			(font
				(size 1.27 1.27)
			)
			(justify left)
		)
	)
	(symbol
		(lib_id "antmicropower:GND")
		(at 259.08 120.65 0)
		(mirror y)
		(unit 1)
		(exclude_from_sim no)
		(in_bom yes)
		(on_board yes)
		(dnp no)
		(property "Reference" "#PWR039"
			(at 250.19 123.19 0)
			(effects
				(font
					(size 1.27 1.27)
					(thickness 0.15)
				)
				(justify left bottom)
				(hide yes)
			)
		)
		(property "Value" "GND"
			(at 259.08 124.46 0)
			(effects
				(font
					(size 1.27 1.27)
					(thickness 0.15)
				)
			)
		)
		(property "Footprint" ""
			(at 250.19 128.27 0)
			(effects
				(font
					(size 1.27 1.27)
					(thickness 0.15)
				)
				(justify left bottom)
				(hide yes)
			)
		)
		(property "Datasheet" ""
			(at 250.19 133.35 0)
			(effects
				(font
					(size 1.27 1.27)
					(thickness 0.15)
				)
				(justify left bottom)
				(hide yes)
			)
		)
		(property "Description" ""
			(at 259.08 120.65 0)
			(effects
				(font
					(size 1.27 1.27)
				)
				(hide yes)
			)
		)
		(property "Author" "Antmicro"
			(at 250.19 128.27 0)
			(effects
				(font
					(size 1.27 1.27)
					(thickness 0.15)
				)
				(justify left bottom)
				(hide yes)
			)
		)
		(property "License" "Apache-2.0"
			(at 250.19 130.81 0)
			(effects
				(font
					(size 1.27 1.27)
					(thickness 0.15)
				)
				(justify left bottom)
				(hide yes)
			)
		)
		(pin "1"
		)
		(instances
			(project "gmsl-serializer"
				(path ""
					(reference "#PWR039")
					(unit 1)
				)
			)
		)
	)
	(symbol
		(lib_id "antmicropower:GND")
		(at 251.46 120.65 0)
		(mirror y)
		(unit 1)
		(exclude_from_sim no)
		(in_bom yes)
		(on_board yes)
		(dnp no)
		(property "Reference" "#PWR034"
			(at 242.57 123.19 0)
			(effects
				(font
					(size 1.27 1.27)
					(thickness 0.15)
				)
				(justify left bottom)
				(hide yes)
			)
		)
		(property "Value" "GND"
			(at 251.46 124.46 0)
			(effects
				(font
					(size 1.27 1.27)
					(thickness 0.15)
				)
			)
		)
		(property "Footprint" ""
			(at 242.57 128.27 0)
			(effects
				(font
					(size 1.27 1.27)
					(thickness 0.15)
				)
				(justify left bottom)
				(hide yes)
			)
		)
		(property "Datasheet" ""
			(at 242.57 133.35 0)
			(effects
				(font
					(size 1.27 1.27)
					(thickness 0.15)
				)
				(justify left bottom)
				(hide yes)
			)
		)
		(property "Description" ""
			(at 251.46 120.65 0)
			(effects
				(font
					(size 1.27 1.27)
				)
				(hide yes)
			)
		)
		(property "Author" "Antmicro"
			(at 242.57 128.27 0)
			(effects
				(font
					(size 1.27 1.27)
					(thickness 0.15)
				)
				(justify left bottom)
				(hide yes)
			)
		)
		(property "License" "Apache-2.0"
			(at 242.57 130.81 0)
			(effects
				(font
					(size 1.27 1.27)
					(thickness 0.15)
				)
				(justify left bottom)
				(hide yes)
			)
		)
		(pin "1"
		)
		(instances
			(project "gmsl-serializer"
				(path ""
					(reference "#PWR034")
					(unit 1)
				)
			)
		)
	)
	(symbol
		(lib_id "antmicroFixedInductors:L_470n_1A_Coilcraft-PFL1609")
		(at 179.07 111.76 0)
		(mirror y)
		(unit 1)
		(exclude_from_sim no)
		(in_bom yes)
		(on_board yes)
		(dnp no)
		(property "Reference" "L6"
			(at 176.53 106.68 0)
			(effects
				(font
					(size 1.27 1.27)
					(thickness 0.15)
				)
			)
		)
		(property "Value" "L_470n_1A_Coilcraft-PFL1609"
			(at 165.1 114.3 0)
			(effects
				(font
					(size 1.27 1.27)
					(thickness 0.15)
				)
				(justify left bottom)
				(hide yes)
			)
		)
		(property "Footprint" "antmicro-footprints:L_Coilcraft-PFL1609"
			(at 165.1 119.38 0)
			(effects
				(font
					(size 1.27 1.27)
					(thickness 0.15)
				)
				(justify left bottom)
				(hide yes)
			)
		)
		(property "Datasheet" "https://www.coilcraft.com/getmedia/2f4cd442-d64d-4413-a518-12fcfd03318d/pfl1609.pdf"
			(at 165.1 121.92 0)
			(effects
				(font
					(size 1.27 1.27)
					(thickness 0.15)
				)
				(justify left bottom)
				(hide yes)
			)
		)
		(property "Description" ""
			(at 179.07 111.76 0)
			(effects
				(font
					(size 1.27 1.27)
				)
				(hide yes)
			)
		)
		(property "Val" "470n/0.99A"
			(at 182.88 110.49 0)
			(effects
				(font
					(size 1.27 1.27)
					(thickness 0.15)
				)
				(justify left bottom)
			)
		)
		(property "Manufacturer" "Coilcraft"
			(at 165.1 124.46 0)
			(effects
				(font
					(size 1.27 1.27)
					(thickness 0.15)
				)
				(justify left bottom)
				(hide yes)
			)
		)
		(property "MPN" "PFL1609-471"
			(at 165.1 127 0)
			(effects
				(font
					(size 1.27 1.27)
					(thickness 0.15)
				)
				(justify left bottom)
				(hide yes)
			)
		)
		(property "ISat" "0.99 A"
			(at 165.1 128.27 0)
			(effects
				(font
					(size 1.27 1.27)
				)
				(justify left)
				(hide yes)
			)
		)
		(property "IMax" "1 A"
			(at 165.1 132.08 0)
			(effects
				(font
					(size 1.27 1.27)
					(thickness 0.15)
				)
				(justify left bottom)
				(hide yes)
			)
		)
		(property "Size" "1.07x1.8"
			(at 165.1 134.62 0)
			(effects
				(font
					(size 1.27 1.27)
					(thickness 0.15)
				)
				(justify left bottom)
				(hide yes)
			)
		)
		(property "Author" "Antmicro"
			(at 165.1 137.16 0)
			(effects
				(font
					(size 1.27 1.27)
					(thickness 0.15)
				)
				(justify left bottom)
				(hide yes)
			)
		)
		(property "License" "Apache-2.0"
			(at 165.1 139.7 0)
			(effects
				(font
					(size 1.27 1.27)
					(thickness 0.15)
				)
				(justify left bottom)
				(hide yes)
			)
		)
		(pin "1"
		)
		(pin "2"
		)
		(instances
			(project "gmsl-serializer"
				(path ""
					(reference "L6")
					(unit 1)
				)
			)
		)
	)
	(symbol
		(lib_id "antmicroResistors0402:R_5k1_0402")
		(at 214.63 121.92 0)
		(mirror y)
		(unit 1)
		(exclude_from_sim no)
		(in_bom yes)
		(on_board yes)
		(dnp no)
		(fields_autoplaced yes)
		(property "Reference" "R17"
			(at 212.09 115.57 0)
			(effects
				(font
					(size 1.27 1.27)
					(thickness 0.15)
				)
			)
		)
		(property "Value" "R_5k1_0402"
			(at 194.31 134.62 0)
			(effects
				(font
					(size 1.27 1.27)
					(thickness 0.15)
				)
				(justify left bottom)
				(hide yes)
			)
		)
		(property "Footprint" "antmicro-footprints:R_0402_1005Metric"
			(at 194.31 137.16 0)
			(effects
				(font
					(size 1.27 1.27)
					(thickness 0.15)
				)
				(justify left bottom)
				(hide yes)
			)
		)
		(property "Datasheet" "https://www.bourns.com/docs/product-datasheets/cr.pdf"
			(at 194.31 139.7 0)
			(effects
				(font
					(size 1.27 1.27)
					(thickness 0.15)
				)
				(justify left bottom)
				(hide yes)
			)
		)
		(property "Description" ""
			(at 214.63 121.92 0)
			(effects
				(font
					(size 1.27 1.27)
				)
				(hide yes)
			)
		)
		(property "MPN" "CR0402-FX-5101GLF"
			(at 194.31 142.24 0)
			(effects
				(font
					(size 1.27 1.27)
					(thickness 0.15)
				)
				(justify left bottom)
				(hide yes)
			)
		)
		(property "Manufacturer" "Bourns"
			(at 194.31 144.78 0)
			(effects
				(font
					(size 1.27 1.27)
					(thickness 0.15)
				)
				(justify left bottom)
				(hide yes)
			)
		)
		(property "License" "Apache-2.0"
			(at 194.31 147.32 0)
			(effects
				(font
					(size 1.27 1.27)
					(thickness 0.15)
				)
				(justify left bottom)
				(hide yes)
			)
		)
		(property "Author" "Antmicro"
			(at 194.31 149.86 0)
			(effects
				(font
					(size 1.27 1.27)
					(thickness 0.15)
				)
				(justify left bottom)
				(hide yes)
			)
		)
		(property "Val" "5k1"
			(at 212.09 118.11 0)
			(effects
				(font
					(size 1.27 1.27)
					(thickness 0.15)
				)
			)
		)
		(property "Tolerance" "1%"
			(at 194.31 132.08 0)
			(effects
				(font
					(size 1.27 1.27)
				)
				(justify left bottom)
				(hide yes)
			)
		)
		(pin "1"
		)
		(pin "2"
		)
		(instances
			(project "gmsl-serializer"
				(path ""
					(reference "R17")
					(unit 1)
				)
			)
		)
	)
	(symbol
		(lib_id "antmicroCapacitors0402:C_10n_0402")
		(at 251.46 119.38 270)
		(mirror x)
		(unit 1)
		(exclude_from_sim no)
		(in_bom yes)
		(on_board yes)
		(dnp no)
		(property "Reference" "C11"
			(at 250.825 114.935 90)
			(effects
				(font
					(size 1.27 1.27)
					(thickness 0.15)
				)
				(justify right)
			)
		)
		(property "Value" "C_10n_0402"
			(at 241.3 99.06 0)
			(effects
				(font
					(size 1.27 1.27)
					(thickness 0.15)
				)
				(justify left bottom)
				(hide yes)
			)
		)
		(property "Footprint" "antmicro-footprints:C_0402_1005Metric"
			(at 238.76 99.06 0)
			(effects
				(font
					(size 1.27 1.27)
					(thickness 0.15)
				)
				(justify left bottom)
				(hide yes)
			)
		)
		(property "Datasheet" "https://www.murata.com/products/productdetail?partno=GRM155R71H103KA88%23"
			(at 236.22 99.06 0)
			(effects
				(font
					(size 1.27 1.27)
					(thickness 0.15)
				)
				(justify left bottom)
				(hide yes)
			)
		)
		(property "Description" ""
			(at 251.46 119.38 0)
			(effects
				(font
					(size 1.27 1.27)
				)
				(hide yes)
			)
		)
		(property "MPN" "GRM155R71H103KA88D"
			(at 233.68 99.06 0)
			(effects
				(font
					(size 1.27 1.27)
					(thickness 0.15)
				)
				(justify left bottom)
				(hide yes)
			)
		)
		(property "Manufacturer" "Murata"
			(at 231.14 99.06 0)
			(effects
				(font
					(size 1.27 1.27)
					(thickness 0.15)
				)
				(justify left bottom)
				(hide yes)
			)
		)
		(property "License" "Apache-2.0"
			(at 228.6 99.06 0)
			(effects
				(font
					(size 1.27 1.27)
					(thickness 0.15)
				)
				(justify left bottom)
				(hide yes)
			)
		)
		(property "Author" "Antmicro"
			(at 226.06 99.06 0)
			(effects
				(font
					(size 1.27 1.27)
					(thickness 0.15)
				)
				(justify left bottom)
				(hide yes)
			)
		)
		(property "Val" "10n"
			(at 250.825 118.745 90)
			(effects
				(font
					(size 1.27 1.27)
					(thickness 0.15)
				)
				(justify right)
			)
		)
		(property "Voltage" "50V"
			(at 223.52 99.06 0)
			(effects
				(font
					(size 1.27 1.27)
				)
				(justify left bottom)
				(hide yes)
			)
		)
		(property "Dielectric" "X7R"
			(at 220.98 99.06 0)
			(effects
				(font
					(size 1.27 1.27)
				)
				(justify left bottom)
				(hide yes)
			)
		)
		(pin "1"
		)
		(pin "2"
		)
		(instances
			(project "gmsl-serializer"
				(path ""
					(reference "C11")
					(unit 1)
				)
			)
		)
	)
	(symbol
		(lib_id "antmicropower:GND")
		(at 120.65 118.11 0)
		(mirror y)
		(unit 1)
		(exclude_from_sim no)
		(in_bom yes)
		(on_board yes)
		(dnp no)
		(property "Reference" "#PWR017"
			(at 111.76 120.65 0)
			(effects
				(font
					(size 1.27 1.27)
					(thickness 0.15)
				)
				(justify left bottom)
				(hide yes)
			)
		)
		(property "Value" "GND"
			(at 120.65 121.92 0)
			(effects
				(font
					(size 1.27 1.27)
					(thickness 0.15)
				)
			)
		)
		(property "Footprint" ""
			(at 111.76 125.73 0)
			(effects
				(font
					(size 1.27 1.27)
					(thickness 0.15)
				)
				(justify left bottom)
				(hide yes)
			)
		)
		(property "Datasheet" ""
			(at 111.76 130.81 0)
			(effects
				(font
					(size 1.27 1.27)
					(thickness 0.15)
				)
				(justify left bottom)
				(hide yes)
			)
		)
		(property "Description" ""
			(at 120.65 118.11 0)
			(effects
				(font
					(size 1.27 1.27)
				)
				(hide yes)
			)
		)
		(property "Author" "Antmicro"
			(at 111.76 125.73 0)
			(effects
				(font
					(size 1.27 1.27)
					(thickness 0.15)
				)
				(justify left bottom)
				(hide yes)
			)
		)
		(property "License" "Apache-2.0"
			(at 111.76 128.27 0)
			(effects
				(font
					(size 1.27 1.27)
					(thickness 0.15)
				)
				(justify left bottom)
				(hide yes)
			)
		)
		(pin "1"
		)
		(instances
			(project "gmsl-serializer"
				(path ""
					(reference "#PWR017")
					(unit 1)
				)
			)
		)
	)
	(symbol
		(lib_id "antmicroFixedInductors:L_6u8_1A_Coilcraft-1210POC")
		(at 214.63 111.76 0)
		(mirror y)
		(unit 1)
		(exclude_from_sim no)
		(in_bom yes)
		(on_board yes)
		(dnp no)
		(property "Reference" "L4"
			(at 212.09 106.68 0)
			(effects
				(font
					(size 1.27 1.27)
					(thickness 0.15)
				)
			)
		)
		(property "Value" "L_6u8_1A_Coilcraft-1210POC"
			(at 200.66 114.3 0)
			(effects
				(font
					(size 1.27 1.27)
					(thickness 0.15)
				)
				(justify left bottom)
				(hide yes)
			)
		)
		(property "Footprint" "antmicro-footprints:L_Coilcraft-1210POC"
			(at 200.66 119.38 0)
			(effects
				(font
					(size 1.27 1.27)
					(thickness 0.15)
				)
				(justify left bottom)
				(hide yes)
			)
		)
		(property "Datasheet" "https://www.coilcraft.com/getmedia/5e8de018-68c5-4442-84ce-d5212c44660c/1210poc.pdf"
			(at 200.66 121.92 0)
			(effects
				(font
					(size 1.27 1.27)
					(thickness 0.15)
				)
				(justify left bottom)
				(hide yes)
			)
		)
		(property "Description" ""
			(at 214.63 111.76 0)
			(effects
				(font
					(size 1.27 1.27)
				)
				(hide yes)
			)
		)
		(property "Val" "6u8/1A"
			(at 215.9 110.49 0)
			(effects
				(font
					(size 1.27 1.27)
					(thickness 0.15)
				)
				(justify left bottom)
			)
		)
		(property "Manufacturer" "Coilcraft"
			(at 200.66 124.46 0)
			(effects
				(font
					(size 1.27 1.27)
					(thickness 0.15)
				)
				(justify left bottom)
				(hide yes)
			)
		)
		(property "MPN" "1210POC-682"
			(at 200.66 127 0)
			(effects
				(font
					(size 1.27 1.27)
					(thickness 0.15)
				)
				(justify left bottom)
				(hide yes)
			)
		)
		(property "ISat" "1 A"
			(at 200.66 128.27 0)
			(effects
				(font
					(size 1.27 1.27)
				)
				(justify left)
				(hide yes)
			)
		)
		(property "IMax" "1.36 A"
			(at 200.66 132.08 0)
			(effects
				(font
					(size 1.27 1.27)
					(thickness 0.15)
				)
				(justify left bottom)
				(hide yes)
			)
		)
		(property "Size" "2.67x3.3"
			(at 200.66 134.62 0)
			(effects
				(font
					(size 1.27 1.27)
					(thickness 0.15)
				)
				(justify left bottom)
				(hide yes)
			)
		)
		(property "Author" "Antmicro"
			(at 200.66 137.16 0)
			(effects
				(font
					(size 1.27 1.27)
					(thickness 0.15)
				)
				(justify left bottom)
				(hide yes)
			)
		)
		(property "License" "Apache-2.0"
			(at 200.66 139.7 0)
			(effects
				(font
					(size 1.27 1.27)
					(thickness 0.15)
				)
				(justify left bottom)
				(hide yes)
			)
		)
		(pin "1"
		)
		(pin "2"
		)
		(instances
			(project "gmsl-serializer"
				(path ""
					(reference "L4")
					(unit 1)
				)
			)
		)
	)
	(symbol
		(lib_id "antmicroTVSDiodes:AXGD10402KR")
		(at 133.35 118.11 270)
		(unit 1)
		(exclude_from_sim no)
		(in_bom yes)
		(on_board yes)
		(dnp no)
		(fields_autoplaced yes)
		(property "Reference" "D2"
			(at 135.89 119.3799 90)
			(effects
				(font
					(size 1.27 1.27)
					(thickness 0.15)
				)
				(justify left)
			)
		)
		(property "Value" "AXGD10402KR"
			(at 123.19 143.51 0)
			(effects
				(font
					(size 1.27 1.27)
					(thickness 0.15)
				)
				(justify left bottom)
				(hide yes)
			)
		)
		(property "Footprint" "antmicro-footprints:D_0402_1005Metric"
			(at 120.65 143.51 0)
			(effects
				(font
					(size 1.27 1.27)
					(thickness 0.15)
				)
				(justify left bottom)
				(hide yes)
			)
		)
		(property "Datasheet" "https://www.littelfuse.com/media?resourcetype=datasheets&itemid=020b2bf2-064c-4ff1-a898-b4ec805b2fea&filename=littelfuse-xtremeguard-axgd-datasheet"
			(at 118.11 143.51 0)
			(effects
				(font
					(size 1.27 1.27)
					(thickness 0.15)
				)
				(justify left bottom)
				(hide yes)
			)
		)
		(property "Description" ""
			(at 133.35 118.11 0)
			(effects
				(font
					(size 1.27 1.27)
				)
				(hide yes)
			)
		)
		(property "Manufacturer" "Littelfuse"
			(at 115.57 143.51 0)
			(effects
				(font
					(size 1.27 1.27)
					(thickness 0.15)
				)
				(justify left bottom)
				(hide yes)
			)
		)
		(property "MPN" "AXGD10402KR"
			(at 135.89 121.9199 90)
			(effects
				(font
					(size 1.27 1.27)
					(thickness 0.15)
				)
				(justify left)
			)
		)
		(property "Author" "Antmicro"
			(at 113.03 143.51 0)
			(effects
				(font
					(size 1.27 1.27)
					(thickness 0.15)
				)
				(justify left bottom)
				(hide yes)
			)
		)
		(property "License" "Apache-2.0"
			(at 110.49 143.51 0)
			(effects
				(font
					(size 1.27 1.27)
					(thickness 0.15)
				)
				(justify left bottom)
				(hide yes)
			)
		)
		(pin "1"
		)
		(pin "2"
		)
		(instances
			(project "gmsl-serializer"
				(path ""
					(reference "D2")
					(unit 1)
				)
			)
		)
	)
	(symbol
		(lib_id "antmicroCoaxialConnectorsRF:Conn_FAKRA_59S2AQ-40MT5-Z_1")
		(at 125.73 111.76 0)
		(mirror y)
		(unit 1)
		(exclude_from_sim no)
		(in_bom yes)
		(on_board yes)
		(dnp no)
		(fields_autoplaced yes)
		(property "Reference" "J2"
			(at 121.0309 105.41 0)
			(effects
				(font
					(size 1.27 1.27)
					(thickness 0.15)
				)
			)
		)
		(property "Value" "Conn_FAKRA_59S2AQ-40MT5-Z_1"
			(at 118.11 114.3 0)
			(effects
				(font
					(size 1.27 1.27)
					(thickness 0.15)
				)
				(justify left)
				(hide yes)
			)
		)
		(property "Footprint" "antmicro-footprints:Conn_FAKRA_59S2AQ-40MT5-Z_1"
			(at 105.41 121.92 0)
			(effects
				(font
					(size 1.27 1.27)
					(thickness 0.15)
				)
				(justify left bottom)
				(hide yes)
			)
		)
		(property "Datasheet" "https://products.rosenberger.com/radio-frequency/connectors/288881/59s2aq-40mt5-z-1-right-angle-plug-pcb-w.-housing"
			(at 105.41 124.46 0)
			(effects
				(font
					(size 1.27 1.27)
					(thickness 0.15)
				)
				(justify left bottom)
				(hide yes)
			)
		)
		(property "Description" ""
			(at 125.73 111.76 0)
			(effects
				(font
					(size 1.27 1.27)
				)
				(hide yes)
			)
		)
		(property "MPN" "59S2AQ-40MT5-Z_1"
			(at 121.0309 107.95 0)
			(effects
				(font
					(size 1.27 1.27)
					(thickness 0.15)
				)
			)
		)
		(property "Manufacturer" "Rosenberger"
			(at 105.41 129.54 0)
			(effects
				(font
					(size 1.27 1.27)
					(thickness 0.15)
				)
				(justify left bottom)
				(hide yes)
			)
		)
		(property "Author" "Antmicro"
			(at 105.41 132.08 0)
			(effects
				(font
					(size 1.27 1.27)
					(thickness 0.15)
				)
				(justify left bottom)
				(hide yes)
			)
		)
		(property "License" "Apache-2.0"
			(at 105.41 134.62 0)
			(effects
				(font
					(size 1.27 1.27)
					(thickness 0.15)
				)
				(justify left bottom)
				(hide yes)
			)
		)
		(pin "1"
		)
		(pin "2"
		)
		(pin "3"
		)
		(pin "4"
		)
		(pin "5"
		)
		(instances
			(project "gmsl-serializer"
				(path ""
					(reference "J2")
					(unit 1)
				)
			)
		)
	)
	(symbol
		(lib_id "antmicropower:GND")
		(at 133.35 125.73 0)
		(mirror y)
		(unit 1)
		(exclude_from_sim no)
		(in_bom yes)
		(on_board yes)
		(dnp no)
		(property "Reference" "#PWR018"
			(at 124.46 128.27 0)
			(effects
				(font
					(size 1.27 1.27)
					(thickness 0.15)
				)
				(justify left bottom)
				(hide yes)
			)
		)
		(property "Value" "GND"
			(at 133.35 129.54 0)
			(effects
				(font
					(size 1.27 1.27)
					(thickness 0.15)
				)
			)
		)
		(property "Footprint" ""
			(at 124.46 133.35 0)
			(effects
				(font
					(size 1.27 1.27)
					(thickness 0.15)
				)
				(justify left bottom)
				(hide yes)
			)
		)
		(property "Datasheet" ""
			(at 124.46 138.43 0)
			(effects
				(font
					(size 1.27 1.27)
					(thickness 0.15)
				)
				(justify left bottom)
				(hide yes)
			)
		)
		(property "Description" ""
			(at 133.35 125.73 0)
			(effects
				(font
					(size 1.27 1.27)
				)
				(hide yes)
			)
		)
		(property "Author" "Antmicro"
			(at 124.46 133.35 0)
			(effects
				(font
					(size 1.27 1.27)
					(thickness 0.15)
				)
				(justify left bottom)
				(hide yes)
			)
		)
		(property "License" "Apache-2.0"
			(at 124.46 135.89 0)
			(effects
				(font
					(size 1.27 1.27)
					(thickness 0.15)
				)
				(justify left bottom)
				(hide yes)
			)
		)
		(pin "1"
		)
		(instances
			(project "gmsl-serializer"
				(path ""
					(reference "#PWR018")
					(unit 1)
				)
			)
		)
	)
	(symbol
		(lib_id "antmicroResistors0402:R_5k1_0402")
		(at 232.41 121.92 0)
		(mirror y)
		(unit 1)
		(exclude_from_sim no)
		(in_bom yes)
		(on_board yes)
		(dnp no)
		(fields_autoplaced yes)
		(property "Reference" "R16"
			(at 229.87 115.57 0)
			(effects
				(font
					(size 1.27 1.27)
					(thickness 0.15)
				)
			)
		)
		(property "Value" "R_5k1_0402"
			(at 212.09 134.62 0)
			(effects
				(font
					(size 1.27 1.27)
					(thickness 0.15)
				)
				(justify left bottom)
				(hide yes)
			)
		)
		(property "Footprint" "antmicro-footprints:R_0402_1005Metric"
			(at 212.09 137.16 0)
			(effects
				(font
					(size 1.27 1.27)
					(thickness 0.15)
				)
				(justify left bottom)
				(hide yes)
			)
		)
		(property "Datasheet" "https://www.bourns.com/docs/product-datasheets/cr.pdf"
			(at 212.09 139.7 0)
			(effects
				(font
					(size 1.27 1.27)
					(thickness 0.15)
				)
				(justify left bottom)
				(hide yes)
			)
		)
		(property "Description" ""
			(at 232.41 121.92 0)
			(effects
				(font
					(size 1.27 1.27)
				)
				(hide yes)
			)
		)
		(property "MPN" "CR0402-FX-5101GLF"
			(at 212.09 142.24 0)
			(effects
				(font
					(size 1.27 1.27)
					(thickness 0.15)
				)
				(justify left bottom)
				(hide yes)
			)
		)
		(property "Manufacturer" "Bourns"
			(at 212.09 144.78 0)
			(effects
				(font
					(size 1.27 1.27)
					(thickness 0.15)
				)
				(justify left bottom)
				(hide yes)
			)
		)
		(property "License" "Apache-2.0"
			(at 212.09 147.32 0)
			(effects
				(font
					(size 1.27 1.27)
					(thickness 0.15)
				)
				(justify left bottom)
				(hide yes)
			)
		)
		(property "Author" "Antmicro"
			(at 212.09 149.86 0)
			(effects
				(font
					(size 1.27 1.27)
					(thickness 0.15)
				)
				(justify left bottom)
				(hide yes)
			)
		)
		(property "Val" "5k1"
			(at 229.87 118.11 0)
			(effects
				(font
					(size 1.27 1.27)
					(thickness 0.15)
				)
			)
		)
		(property "Tolerance" "1%"
			(at 212.09 132.08 0)
			(effects
				(font
					(size 1.27 1.27)
				)
				(justify left bottom)
				(hide yes)
			)
		)
		(pin "1"
		)
		(pin "2"
		)
		(instances
			(project "gmsl-serializer"
				(path ""
					(reference "R16")
					(unit 1)
				)
			)
		)
	)
	(symbol
		(lib_id "antmicroFixedInductors:L_22u_1.12A_Coilcraft-MSS6132T")
		(at 232.41 111.76 0)
		(mirror y)
		(unit 1)
		(exclude_from_sim no)
		(in_bom yes)
		(on_board yes)
		(dnp no)
		(property "Reference" "L3"
			(at 229.87 106.68 0)
			(effects
				(font
					(size 1.27 1.27)
					(thickness 0.15)
				)
			)
		)
		(property "Value" "L_22u_1.12A_Coilcraft-MSS6132T"
			(at 218.44 114.3 0)
			(effects
				(font
					(size 1.27 1.27)
					(thickness 0.15)
				)
				(justify left bottom)
				(hide yes)
			)
		)
		(property "Footprint" "antmicro-footprints:L_Coilcraft-MSS6132T"
			(at 218.44 119.38 0)
			(effects
				(font
					(size 1.27 1.27)
					(thickness 0.15)
				)
				(justify left bottom)
				(hide yes)
			)
		)
		(property "Datasheet" "https://www.coilcraft.com/getmedia/d035c9b3-191d-46aa-ab3f-5c1a849157c1/mss6132t.pdf"
			(at 218.44 121.92 0)
			(effects
				(font
					(size 1.27 1.27)
					(thickness 0.15)
				)
				(justify left bottom)
				(hide yes)
			)
		)
		(property "Description" ""
			(at 232.41 111.76 0)
			(effects
				(font
					(size 1.27 1.27)
				)
				(hide yes)
			)
		)
		(property "Val" "22u/1.12A"
			(at 234.95 110.49 0)
			(effects
				(font
					(size 1.27 1.27)
					(thickness 0.15)
				)
				(justify left bottom)
			)
		)
		(property "Manufacturer" "Coilcraft"
			(at 218.44 124.46 0)
			(effects
				(font
					(size 1.27 1.27)
					(thickness 0.15)
				)
				(justify left bottom)
				(hide yes)
			)
		)
		(property "MPN" "MSS6132T-223"
			(at 218.44 127 0)
			(effects
				(font
					(size 1.27 1.27)
					(thickness 0.15)
				)
				(justify left bottom)
				(hide yes)
			)
		)
		(property "ISat" "1.12A"
			(at 218.44 128.27 0)
			(effects
				(font
					(size 1.27 1.27)
				)
				(justify left)
				(hide yes)
			)
		)
		(property "IMax" "1.45A"
			(at 218.44 132.08 0)
			(effects
				(font
					(size 1.27 1.27)
					(thickness 0.15)
				)
				(justify left bottom)
				(hide yes)
			)
		)
		(property "Size" "6.1x6.1"
			(at 218.44 134.62 0)
			(effects
				(font
					(size 1.27 1.27)
					(thickness 0.15)
				)
				(justify left bottom)
				(hide yes)
			)
		)
		(property "Author" "Antmicro"
			(at 218.44 137.16 0)
			(effects
				(font
					(size 1.27 1.27)
					(thickness 0.15)
				)
				(justify left bottom)
				(hide yes)
			)
		)
		(property "License" "Apache-2.0"
			(at 218.44 139.7 0)
			(effects
				(font
					(size 1.27 1.27)
					(thickness 0.15)
				)
				(justify left bottom)
				(hide yes)
			)
		)
		(pin "1"
		)
		(pin "2"
		)
		(instances
			(project "gmsl-serializer"
				(path ""
					(reference "L3")
					(unit 1)
				)
			)
		)
	)
	(symbol
		(lib_id "antmicroTestPoints:TP_1.5mm_SMD")
		(at 246.38 110.49 270)
		(mirror x)
		(unit 1)
		(exclude_from_sim no)
		(in_bom no)
		(on_board yes)
		(dnp no)
		(property "Reference" "TP3"
			(at 248.92 105.41 90)
			(effects
				(font
					(size 1.27 1.27)
					(thickness 0.15)
				)
				(justify right)
			)
		)
		(property "Value" "TP_1.5mm_SMD"
			(at 238.76 95.25 0)
			(effects
				(font
					(size 1.27 1.27)
					(thickness 0.15)
				)
				(justify left bottom)
				(hide yes)
			)
		)
		(property "Footprint" "antmicro-footprints:TP_SMD_1.5mm"
			(at 236.22 95.25 0)
			(effects
				(font
					(size 1.27 1.27)
					(thickness 0.15)
				)
				(justify left bottom)
				(hide yes)
			)
		)
		(property "Datasheet" ""
			(at 233.68 92.71 0)
			(effects
				(font
					(size 1.27 1.27)
					(thickness 0.15)
				)
				(justify left bottom)
				(hide yes)
			)
		)
		(property "Description" ""
			(at 246.38 110.49 0)
			(effects
				(font
					(size 1.27 1.27)
				)
				(hide yes)
			)
		)
		(property "MPN" ""
			(at 246.38 110.49 0)
			(effects
				(font
					(size 1.27 1.27)
				)
				(hide yes)
			)
		)
		(property "Manufacturer" ""
			(at 246.38 110.49 0)
			(effects
				(font
					(size 1.27 1.27)
				)
				(hide yes)
			)
		)
		(property "Author" "Antmicro"
			(at 231.14 95.25 0)
			(effects
				(font
					(size 1.27 1.27)
					(thickness 0.15)
				)
				(justify left bottom)
				(hide yes)
			)
		)
		(property "License" "Apache-2.0"
			(at 228.6 95.25 0)
			(effects
				(font
					(size 1.27 1.27)
					(thickness 0.15)
				)
				(justify left bottom)
				(hide yes)
			)
		)
		(pin "1"
		)
		(instances
			(project "gmsl-serializer"
				(path ""
					(reference "TP3")
					(unit 1)
				)
			)
		)
	)
	(symbol
		(lib_id "antmicroFixedInductors:L_470n_1A_Coilcraft-PFL1609")
		(at 196.85 111.76 0)
		(mirror y)
		(unit 1)
		(exclude_from_sim no)
		(in_bom yes)
		(on_board yes)
		(dnp no)
		(property "Reference" "L5"
			(at 194.31 106.68 0)
			(effects
				(font
					(size 1.27 1.27)
					(thickness 0.15)
				)
			)
		)
		(property "Value" "L_470n_1A_Coilcraft-PFL1609"
			(at 182.88 114.3 0)
			(effects
				(font
					(size 1.27 1.27)
					(thickness 0.15)
				)
				(justify left bottom)
				(hide yes)
			)
		)
		(property "Footprint" "antmicro-footprints:L_Coilcraft-PFL1609"
			(at 182.88 119.38 0)
			(effects
				(font
					(size 1.27 1.27)
					(thickness 0.15)
				)
				(justify left bottom)
				(hide yes)
			)
		)
		(property "Datasheet" "https://www.coilcraft.com/getmedia/2f4cd442-d64d-4413-a518-12fcfd03318d/pfl1609.pdf"
			(at 182.88 121.92 0)
			(effects
				(font
					(size 1.27 1.27)
					(thickness 0.15)
				)
				(justify left bottom)
				(hide yes)
			)
		)
		(property "Description" ""
			(at 196.85 111.76 0)
			(effects
				(font
					(size 1.27 1.27)
				)
				(hide yes)
			)
		)
		(property "Val" "470n/0.99A"
			(at 200.66 110.49 0)
			(effects
				(font
					(size 1.27 1.27)
					(thickness 0.15)
				)
				(justify left bottom)
			)
		)
		(property "Manufacturer" "Coilcraft"
			(at 182.88 124.46 0)
			(effects
				(font
					(size 1.27 1.27)
					(thickness 0.15)
				)
				(justify left bottom)
				(hide yes)
			)
		)
		(property "MPN" "PFL1609-471"
			(at 182.88 127 0)
			(effects
				(font
					(size 1.27 1.27)
					(thickness 0.15)
				)
				(justify left bottom)
				(hide yes)
			)
		)
		(property "ISat" "0.99 A"
			(at 182.88 128.27 0)
			(effects
				(font
					(size 1.27 1.27)
				)
				(justify left)
				(hide yes)
			)
		)
		(property "IMax" "1 A"
			(at 182.88 132.08 0)
			(effects
				(font
					(size 1.27 1.27)
					(thickness 0.15)
				)
				(justify left bottom)
				(hide yes)
			)
		)
		(property "Size" "1.07x1.8"
			(at 182.88 134.62 0)
			(effects
				(font
					(size 1.27 1.27)
					(thickness 0.15)
				)
				(justify left bottom)
				(hide yes)
			)
		)
		(property "Author" "Antmicro"
			(at 182.88 137.16 0)
			(effects
				(font
					(size 1.27 1.27)
					(thickness 0.15)
				)
				(justify left bottom)
				(hide yes)
			)
		)
		(property "License" "Apache-2.0"
			(at 182.88 139.7 0)
			(effects
				(font
					(size 1.27 1.27)
					(thickness 0.15)
				)
				(justify left bottom)
				(hide yes)
			)
		)
		(pin "1"
		)
		(pin "2"
		)
		(instances
			(project "gmsl-serializer"
				(path ""
					(reference "L5")
					(unit 1)
				)
			)
		)
	)
	(symbol
		(lib_id "antmicroCapacitors0402:C_100n_0402")
		(at 259.08 119.38 270)
		(mirror x)
		(unit 1)
		(exclude_from_sim no)
		(in_bom yes)
		(on_board yes)
		(dnp no)
		(property "Reference" "C10"
			(at 258.445 114.935 90)
			(effects
				(font
					(size 1.27 1.27)
					(thickness 0.15)
				)
				(justify right)
			)
		)
		(property "Value" "C_100n_0402"
			(at 248.92 99.06 0)
			(effects
				(font
					(size 1.27 1.27)
					(thickness 0.15)
				)
				(justify left bottom)
				(hide yes)
			)
		)
		(property "Footprint" "antmicro-footprints:C_0402_1005Metric"
			(at 246.38 99.06 0)
			(effects
				(font
					(size 1.27 1.27)
					(thickness 0.15)
				)
				(justify left bottom)
				(hide yes)
			)
		)
		(property "Datasheet" "https://www.murata.com/products/productdetail?partno=GRM155R61H104KE14%23"
			(at 243.84 99.06 0)
			(effects
				(font
					(size 1.27 1.27)
					(thickness 0.15)
				)
				(justify left bottom)
				(hide yes)
			)
		)
		(property "Description" ""
			(at 259.08 119.38 0)
			(effects
				(font
					(size 1.27 1.27)
				)
				(hide yes)
			)
		)
		(property "MPN" "GRM155R61H104KE14D"
			(at 241.3 99.06 0)
			(effects
				(font
					(size 1.27 1.27)
					(thickness 0.15)
				)
				(justify left bottom)
				(hide yes)
			)
		)
		(property "Manufacturer" "Murata"
			(at 238.76 99.06 0)
			(effects
				(font
					(size 1.27 1.27)
					(thickness 0.15)
				)
				(justify left bottom)
				(hide yes)
			)
		)
		(property "License" "Apache-2.0"
			(at 236.22 99.06 0)
			(effects
				(font
					(size 1.27 1.27)
					(thickness 0.15)
				)
				(justify left bottom)
				(hide yes)
			)
		)
		(property "Author" "Antmicro"
			(at 233.68 99.06 0)
			(effects
				(font
					(size 1.27 1.27)
					(thickness 0.15)
				)
				(justify left bottom)
				(hide yes)
			)
		)
		(property "Val" "100n"
			(at 258.445 118.745 90)
			(effects
				(font
					(size 1.27 1.27)
					(thickness 0.15)
				)
				(justify right)
			)
		)
		(property "Voltage" "50V"
			(at 231.14 99.06 0)
			(effects
				(font
					(size 1.27 1.27)
				)
				(justify left bottom)
				(hide yes)
			)
		)
		(property "Dielectric" "X5R"
			(at 228.6 99.06 0)
			(effects
				(font
					(size 1.27 1.27)
				)
				(justify left bottom)
				(hide yes)
			)
		)
		(pin "1"
		)
		(pin "2"
		)
		(instances
			(project "gmsl-serializer"
				(path ""
					(reference "C10")
					(unit 1)
				)
			)
		)
	)
	(symbol
		(lib_id "antmicropower:+12V")
		(at 259.08 110.49 0)
		(mirror y)
		(unit 1)
		(exclude_from_sim no)
		(in_bom yes)
		(on_board yes)
		(dnp no)
		(fields_autoplaced yes)
		(property "Reference" "#PWR038"
			(at 259.08 114.3 0)
			(effects
				(font
					(size 1.27 1.27)
				)
				(hide yes)
			)
		)
		(property "Value" "+12V"
			(at 259.08 105.41 0)
			(effects
				(font
					(size 1.27 1.27)
				)
			)
		)
		(property "Footprint" ""
			(at 259.08 110.49 0)
			(effects
				(font
					(size 1.27 1.27)
				)
				(hide yes)
			)
		)
		(property "Datasheet" ""
			(at 259.08 110.49 0)
			(effects
				(font
					(size 1.27 1.27)
				)
				(hide yes)
			)
		)
		(property "Description" ""
			(at 259.08 110.49 0)
			(effects
				(font
					(size 1.27 1.27)
				)
				(hide yes)
			)
		)
		(pin "1"
		)
		(instances
			(project "gmsl-serializer"
				(path ""
					(reference "#PWR038")
					(unit 1)
				)
			)
		)
	)
)
